(kicad_pcb
	(version 20260206)
	(generator "pcbnew")
	(generator_version "10.0")
	(general
		(thickness 1.6)
		(legacy_teardrops no)
	)
	(paper "A4")
	(title_block
		(title "04192023_DAF0TMB3IC0_F0TG_MB_C_brd_V02_OCP.brd")
		(comment 1 "Grand Teton / footprints 4322-4328 of 8354")
	)
	(layers
		(0 "F.Cu" signal "TOP")
		(4 "In1.Cu" signal "GND")
		(6 "In2.Cu" signal "IN1")
		(8 "In3.Cu" signal "GND1")
		(10 "In4.Cu" signal "IN2")
		(12 "In5.Cu" signal "GND2")
		(14 "In6.Cu" signal "IN3")
		(16 "In7.Cu" signal "GND3")
		(18 "In8.Cu" signal "VCC")
		(20 "In9.Cu" signal "VCC1")
		(22 "In10.Cu" signal "GND4")
		(24 "In11.Cu" signal "IN4")
		(26 "In12.Cu" signal "GND5")
		(28 "In13.Cu" signal "IN5")
		(30 "In14.Cu" signal "GND6")
		(32 "In15.Cu" signal "IN6")
		(34 "In16.Cu" signal "GND7")
		(2 "B.Cu" signal "BOTTOM")
		(9 "F.Adhes" user "F.Adhesive")
		(11 "B.Adhes" user "B.Adhesive")
		(13 "F.Paste" user "Package Geometry/Pastemask Top")
		(15 "B.Paste" user "Package Geometry/Pastemask Bottom")
		(5 "F.SilkS" user "Ref Des/Silkscreen Top")
		(7 "B.SilkS" user "Ref Des/Silkscreen Bottom")
		(1 "F.Mask" user "Board Geometry/Soldermask Top")
		(3 "B.Mask" user "Board Geometry/Soldermask Bottom")
		(17 "Dwgs.User" user "User.Drawings")
		(19 "Cmts.User" user "User.Comments")
		(21 "Eco1.User" user "User.Eco1")
		(23 "Eco2.User" user "User.Eco2")
		(25 "Edge.Cuts" user "Board Geometry/Outline")
		(27 "Margin" user)
		(31 "F.CrtYd" user "Package Geometry/Place Bound Top")
		(29 "B.CrtYd" user "Package Geometry/Place Bound Bottom")
		(35 "F.Fab" user "Ref Des/Assembly Top")
		(33 "B.Fab" user "Ref Des/Assembly Bottom")
	)
	(footprint ""
		(layer "F.Cu")
		(at 322.837048 -42.176954 180)
		(property "Reference" "R3684"
			(at 0 0 180)
			(layer "F.SilkS")
			(hide yes)
			(effects
				(font
					(size 1.27 1.27)
				)
			)
		)
		(property "Value" ""
			(at 0 0 180)
			(layer "F.Fab")
			(effects
				(font
					(size 1.27 1.27)
				)
			)
		)
		(duplicate_pad_numbers_are_jumpers no)
		(fp_line
			(start 0.7874 0.4064)
			(end -0.7874 0.4064)
			(stroke
				(width 0.1524)
				(type default)
			)
			(layer "F.SilkS")
		)
		(fp_line
			(start 0.7874 -0.4064)
			(end 0.7874 0.4064)
			(stroke
				(width 0.1524)
				(type default)
			)
			(layer "F.SilkS")
		)
		(fp_line
			(start -0.7874 0.4064)
			(end -0.7874 -0.4064)
			(stroke
				(width 0.1524)
				(type default)
			)
			(layer "F.SilkS")
		)
		(fp_line
			(start -0.7874 -0.4064)
			(end 0.7874 -0.4064)
			(stroke
				(width 0.1524)
				(type default)
			)
			(layer "F.SilkS")
		)
		(fp_line
			(start 0.67945 0.3048)
			(end 0.120396 0.3048)
			(stroke
				(width 0.1)
				(type default)
			)
			(layer "F.Fab")
		)
		(fp_line
			(start 0.67945 -0.3048)
			(end 0.67945 0.3048)
			(stroke
				(width 0.1)
				(type default)
			)
			(layer "F.Fab")
		)
		(fp_line
			(start 0.12065 -0.2794)
			(end 0.12065 -0.3048)
			(stroke
				(width 0.1)
				(type default)
			)
			(layer "F.Fab")
		)
		(fp_line
			(start 0.12065 -0.3048)
			(end 0.67945 -0.3048)
			(stroke
				(width 0.1)
				(type default)
			)
			(layer "F.Fab")
		)
		(fp_line
			(start 0.120396 0.3048)
			(end 0.120396 0.2794)
			(stroke
				(width 0.1)
				(type default)
			)
			(layer "F.Fab")
		)
		(fp_line
			(start 0.120396 0.2794)
			(end -0.12065 0.2794)
			(stroke
				(width 0.1)
				(type default)
			)
			(layer "F.Fab")
		)
		(fp_line
			(start -0.12065 0.3048)
			(end -0.67945 0.3048)
			(stroke
				(width 0.1)
				(type default)
			)
			(layer "F.Fab")
		)
		(fp_line
			(start -0.12065 0.2794)
			(end -0.12065 0.3048)
			(stroke
				(width 0.1)
				(type default)
			)
			(layer "F.Fab")
		)
		(fp_line
			(start -0.12065 -0.2794)
			(end 0.12065 -0.2794)
			(stroke
				(width 0.1)
				(type default)
			)
			(layer "F.Fab")
		)
		(fp_line
			(start -0.12065 -0.305054)
			(end -0.12065 -0.2794)
			(stroke
				(width 0.1)
				(type default)
			)
			(layer "F.Fab")
		)
		(fp_line
			(start -0.67945 0.3048)
			(end -0.67945 -0.305054)
			(stroke
				(width 0.1)
				(type default)
			)
			(layer "F.Fab")
		)
		(fp_line
			(start -0.67945 -0.305054)
			(end -0.12065 -0.305054)
			(stroke
				(width 0.1)
				(type default)
			)
			(layer "F.Fab")
		)
		(pad "1" smd rect
			(at -0.40005 0)
			(size 0.4572 0.508)
			(layers "F.Cu" "F.Mask" "F.Paste")
			(net "P3V3_ADC")
		)
		(pad "2" smd rect
			(at 0.40005 0)
			(size 0.4572 0.508)
			(layers "F.Cu" "F.Mask" "F.Paste")
			(net "P3V3_ADC_TIC")
		)
	)
	(footprint ""
		(layer "F.Cu")
		(at 24.765 -357.632)
		(property "Reference" "PR239"
			(at 0 0 0)
			(layer "F.SilkS")
			(hide yes)
			(effects
				(font
					(size 1.27 1.27)
				)
			)
		)
		(property "Value" ""
			(at 0 0 0)
			(layer "F.Fab")
			(effects
				(font
					(size 1.27 1.27)
				)
			)
		)
		(duplicate_pad_numbers_are_jumpers no)
		(fp_line
			(start -0.7874 -0.4064)
			(end 0.7874 -0.4064)
			(stroke
				(width 0.1524)
				(type default)
			)
			(layer "F.SilkS")
		)
		(fp_line
			(start -0.7874 0.4064)
			(end -0.7874 -0.4064)
			(stroke
				(width 0.1524)
				(type default)
			)
			(layer "F.SilkS")
		)
		(fp_line
			(start 0.7874 -0.4064)
			(end 0.7874 0.4064)
			(stroke
				(width 0.1524)
				(type default)
			)
			(layer "F.SilkS")
		)
		(fp_line
			(start 0.7874 0.4064)
			(end -0.7874 0.4064)
			(stroke
				(width 0.1524)
				(type default)
			)
			(layer "F.SilkS")
		)
		(fp_line
			(start -0.67945 -0.305054)
			(end -0.12065 -0.305054)
			(stroke
				(width 0.1)
				(type default)
			)
			(layer "F.Fab")
		)
		(fp_line
			(start -0.67945 0.3048)
			(end -0.67945 -0.305054)
			(stroke
				(width 0.1)
				(type default)
			)
			(layer "F.Fab")
		)
		(fp_line
			(start -0.12065 -0.305054)
			(end -0.12065 -0.2794)
			(stroke
				(width 0.1)
				(type default)
			)
			(layer "F.Fab")
		)
		(fp_line
			(start -0.12065 -0.2794)
			(end 0.12065 -0.2794)
			(stroke
				(width 0.1)
				(type default)
			)
			(layer "F.Fab")
		)
		(fp_line
			(start -0.12065 0.2794)
			(end -0.12065 0.3048)
			(stroke
				(width 0.1)
				(type default)
			)
			(layer "F.Fab")
		)
		(fp_line
			(start -0.12065 0.3048)
			(end -0.67945 0.3048)
			(stroke
				(width 0.1)
				(type default)
			)
			(layer "F.Fab")
		)
		(fp_line
			(start 0.120396 0.2794)
			(end -0.12065 0.2794)
			(stroke
				(width 0.1)
				(type default)
			)
			(layer "F.Fab")
		)
		(fp_line
			(start 0.120396 0.3048)
			(end 0.120396 0.2794)
			(stroke
				(width 0.1)
				(type default)
			)
			(layer "F.Fab")
		)
		(fp_line
			(start 0.12065 -0.3048)
			(end 0.67945 -0.3048)
			(stroke
				(width 0.1)
				(type default)
			)
			(layer "F.Fab")
		)
		(fp_line
			(start 0.12065 -0.2794)
			(end 0.12065 -0.3048)
			(stroke
				(width 0.1)
				(type default)
			)
			(layer "F.Fab")
		)
		(fp_line
			(start 0.67945 -0.3048)
			(end 0.67945 0.3048)
			(stroke
				(width 0.1)
				(type default)
			)
			(layer "F.Fab")
		)
		(fp_line
			(start 0.67945 0.3048)
			(end 0.120396 0.3048)
			(stroke
				(width 0.1)
				(type default)
			)
			(layer "F.Fab")
		)
		(pad "1" smd circle
			(at -0.40005 0)
			(size 0 0)
			(layers "F.Cu" "F.Mask" "F.Paste")
			(net "SVID_PVDDCR_CPU1_P1_SVTI")
		)
		(pad "2" smd circle
			(at 0.40005 0)
			(size 0 0)
			(layers "F.Cu" "F.Mask" "F.Paste")
			(net "SVID_PVDDCR_CPU1_P1_SVTI_R")
		)
	)
	(footprint ""
		(layer "F.Cu")
		(at 384.809492 -383.88163 -90)
		(property "Reference" "C881"
			(at 0 0 270)
			(layer "F.SilkS")
			(hide yes)
			(effects
				(font
					(size 1.27 1.27)
				)
			)
		)
		(property "Value" ""
			(at 0 0 270)
			(layer "F.Fab")
			(effects
				(font
					(size 1.27 1.27)
				)
			)
		)
		(duplicate_pad_numbers_are_jumpers no)
		(fp_line
			(start -0.299974 0.150114)
			(end -0.299974 -0.150114)
			(stroke
				(width 0.1)
				(type default)
			)
			(layer "F.Fab")
		)
		(fp_line
			(start 0.299974 0.150114)
			(end -0.299974 0.150114)
			(stroke
				(width 0.1)
				(type default)
			)
			(layer "F.Fab")
		)
		(fp_line
			(start -0.299974 -0.150114)
			(end 0.299974 -0.150114)
			(stroke
				(width 0.1)
				(type default)
			)
			(layer "F.Fab")
		)
		(fp_line
			(start 0.299974 -0.150114)
			(end 0.299974 0.150114)
			(stroke
				(width 0.1)
				(type default)
			)
			(layer "F.Fab")
		)
		(pad "1" smd rect
			(at -0.2667 0 270)
			(size 0.3048 0.381)
			(layers "F.Cu" "F.Mask" "F.Paste")
			(net "P5E_CPU0_P3_TX_C_DP<10>")
		)
		(pad "2" smd rect
			(at 0.2667 0 270)
			(size 0.3048 0.381)
			(layers "F.Cu" "F.Mask" "F.Paste")
			(net "P5E_CPU0_P3_TX_DP<10>")
		)
	)
	(footprint ""
		(layer "F.Cu")
		(at 479.262948 -23.903178)
		(property "Reference" "DB9"
			(at 1.276096 2.670556 0)
			(unlocked yes)
			(layer "F.SilkS")
			(effects
				(font
					(size 0.7874 0.5842)
					(thickness 0.1524)
				)
				(justify left)
			)
		)
		(property "Value" ""
			(at 0 0 0)
			(layer "F.Fab")
			(effects
				(font
					(size 1.27 1.27)
				)
			)
		)
		(duplicate_pad_numbers_are_jumpers no)
		(fp_line
			(start -3.330702 -4.771136)
			(end 3.330702 -4.771136)
			(stroke
				(width 0.1524)
				(type default)
			)
			(layer "F.SilkS")
		)
		(fp_line
			(start 0 4.011168)
			(end -3.330702 -4.771136)
			(stroke
				(width 0.1524)
				(type default)
			)
			(layer "F.SilkS")
		)
		(fp_line
			(start 3.330702 -4.771136)
			(end 0 4.011168)
			(stroke
				(width 0.1524)
				(type default)
			)
			(layer "F.SilkS")
		)
		(fp_line
			(start -3.330702 -4.771136)
			(end 3.330702 -4.771136)
			(stroke
				(width 0.1)
				(type default)
			)
			(layer "F.Fab")
		)
		(fp_line
			(start 0 4.011168)
			(end -3.330702 -4.771136)
			(stroke
				(width 0.1)
				(type default)
			)
			(layer "F.Fab")
		)
		(fp_line
			(start 3.330702 -4.771136)
			(end 0 4.011168)
			(stroke
				(width 0.1)
				(type default)
			)
			(layer "F.Fab")
		)
		(pad "1" thru_hole circle
			(at 0 0)
			(size 2.159 2.159)
			(drill 1.7018)
			(layers "*.Cu" "*.Mask")
			(remove_unused_layers no)
			(net "T1_GND")
			(clearance 0.0254)
			(thermal_gap 0.0254)
		)
		(pad "2" thru_hole circle
			(at -1.27 -3.348736)
			(size 2.159 2.159)
			(drill 1.7018)
			(layers "*.Cu" "*.Mask")
			(remove_unused_layers no)
			(net "TDR_SE_50_OHM_IN2")
			(clearance 0.0254)
			(thermal_gap 0.0254)
		)
		(pad "3" thru_hole circle
			(at 1.27 -3.348736)
			(size 2.159 2.159)
			(drill 1.7018)
			(layers "*.Cu" "*.Mask")
			(remove_unused_layers no)
			(net "TDR_SE_50_OHM_IN2")
			(clearance 0.0254)
			(thermal_gap 0.0254)
		)
	)
	(footprint ""
		(layer "F.Cu")
		(at 184.455054 -169.118026 -90)
		(property "Reference" "R1337"
			(at 0 0 270)
			(layer "F.SilkS")
			(hide yes)
			(effects
				(font
					(size 1.27 1.27)
				)
			)
		)
		(property "Value" ""
			(at 0 0 270)
			(layer "F.Fab")
			(effects
				(font
					(size 1.27 1.27)
				)
			)
		)
		(duplicate_pad_numbers_are_jumpers no)
		(fp_line
			(start -0.7874 0.4064)
			(end -0.7874 -0.4064)
			(stroke
				(width 0.1524)
				(type default)
			)
			(layer "F.SilkS")
		)
		(fp_line
			(start 0.7874 0.4064)
			(end -0.7874 0.4064)
			(stroke
				(width 0.1524)
				(type default)
			)
			(layer "F.SilkS")
		)
		(fp_line
			(start -0.7874 -0.4064)
			(end 0.7874 -0.4064)
			(stroke
				(width 0.1524)
				(type default)
			)
			(layer "F.SilkS")
		)
		(fp_line
			(start 0.7874 -0.4064)
			(end 0.7874 0.4064)
			(stroke
				(width 0.1524)
				(type default)
			)
			(layer "F.SilkS")
		)
		(fp_line
			(start -0.67945 0.3048)
			(end -0.67945 -0.305054)
			(stroke
				(width 0.1)
				(type default)
			)
			(layer "F.Fab")
		)
		(fp_line
			(start -0.12065 0.3048)
			(end -0.67945 0.3048)
			(stroke
				(width 0.1)
				(type default)
			)
			(layer "F.Fab")
		)
		(fp_line
			(start 0.120396 0.3048)
			(end 0.120396 0.2794)
			(stroke
				(width 0.1)
				(type default)
			)
			(layer "F.Fab")
		)
		(fp_line
			(start 0.67945 0.3048)
			(end 0.120396 0.3048)
			(stroke
				(width 0.1)
				(type default)
			)
			(layer "F.Fab")
		)
		(fp_line
			(start -0.12065 0.2794)
			(end -0.12065 0.3048)
			(stroke
				(width 0.1)
				(type default)
			)
			(layer "F.Fab")
		)
		(fp_line
			(start 0.120396 0.2794)
			(end -0.12065 0.2794)
			(stroke
				(width 0.1)
				(type default)
			)
			(layer "F.Fab")
		)
		(fp_line
			(start -0.12065 -0.2794)
			(end 0.12065 -0.2794)
			(stroke
				(width 0.1)
				(type default)
			)
			(layer "F.Fab")
		)
		(fp_line
			(start 0.12065 -0.2794)
			(end 0.12065 -0.3048)
			(stroke
				(width 0.1)
				(type default)
			)
			(layer "F.Fab")
		)
		(fp_line
			(start 0.12065 -0.3048)
			(end 0.67945 -0.3048)
			(stroke
				(width 0.1)
				(type default)
			)
			(layer "F.Fab")
		)
		(fp_line
			(start 0.67945 -0.3048)
			(end 0.67945 0.3048)
			(stroke
				(width 0.1)
				(type default)
			)
			(layer "F.Fab")
		)
		(fp_line
			(start -0.67945 -0.305054)
			(end -0.12065 -0.305054)
			(stroke
				(width 0.1)
				(type default)
			)
			(layer "F.Fab")
		)
		(fp_line
			(start -0.12065 -0.305054)
			(end -0.12065 -0.2794)
			(stroke
				(width 0.1)
				(type default)
			)
			(layer "F.Fab")
		)
		(pad "1" smd rect
			(at -0.40005 0 90)
			(size 0.4572 0.508)
			(layers "F.Cu" "F.Mask" "F.Paste")
			(net "I3C_SPD_DDRGL_CPU1_BYPASS_SDA")
		)
		(pad "2" smd rect
			(at 0.40005 0 90)
			(size 0.4572 0.508)
			(layers "F.Cu" "F.Mask" "F.Paste")
			(net "I3C_SPD_DDRGL_CPU1_SDA")
		)
	)
	(footprint ""
		(layer "F.Cu")
		(at 169.368724 -376.982228)
		(property "Reference" "C744"
			(at 0 0 0)
			(layer "F.SilkS")
			(hide yes)
			(effects
				(font
					(size 1.27 1.27)
				)
			)
		)
		(property "Value" ""
			(at 0 0 0)
			(layer "F.Fab")
			(effects
				(font
					(size 1.27 1.27)
				)
			)
		)
		(duplicate_pad_numbers_are_jumpers no)
		(fp_line
			(start -0.299974 -0.150114)
			(end 0.299974 -0.150114)
			(stroke
				(width 0.1)
				(type default)
			)
			(layer "F.Fab")
		)
		(fp_line
			(start -0.299974 0.150114)
			(end -0.299974 -0.150114)
			(stroke
				(width 0.1)
				(type default)
			)
			(layer "F.Fab")
		)
		(fp_line
			(start 0.299974 -0.150114)
			(end 0.299974 0.150114)
			(stroke
				(width 0.1)
				(type default)
			)
			(layer "F.Fab")
		)
		(fp_line
			(start 0.299974 0.150114)
			(end -0.299974 0.150114)
			(stroke
				(width 0.1)
				(type default)
			)
			(layer "F.Fab")
		)
		(pad "1" smd rect
			(at -0.2667 0)
			(size 0.3048 0.381)
			(layers "F.Cu" "F.Mask" "F.Paste")
			(net "P5E_CPU1_P2_TX_C_DN<14>")
		)
		(pad "2" smd rect
			(at 0.2667 0)
			(size 0.3048 0.381)
			(layers "F.Cu" "F.Mask" "F.Paste")
			(net "P5E_CPU1_P2_TX_DN<14>")
		)
	)
	(footprint ""
		(layer "F.Cu")
		(at 229.560374 -154.15641)
		(property "Reference" "R6104"
			(at 0 0 0)
			(layer "F.SilkS")
			(hide yes)
			(effects
				(font
					(size 1.27 1.27)
				)
			)
		)
		(property "Value" ""
			(at 0 0 0)
			(layer "F.Fab")
			(effects
				(font
					(size 1.27 1.27)
				)
			)
		)
		(duplicate_pad_numbers_are_jumpers no)
		(fp_line
			(start -0.7874 -0.4064)
			(end 0.7874 -0.4064)
			(stroke
				(width 0.1524)
				(type default)
			)
			(layer "F.SilkS")
		)
		(fp_line
			(start -0.7874 0.4064)
			(end -0.7874 -0.4064)
			(stroke
				(width 0.1524)
				(type default)
			)
			(layer "F.SilkS")
		)
		(fp_line
			(start 0.7874 -0.4064)
			(end 0.7874 0.4064)
			(stroke
				(width 0.1524)
				(type default)
			)
			(layer "F.SilkS")
		)
		(fp_line
			(start 0.7874 0.4064)
			(end -0.7874 0.4064)
			(stroke
				(width 0.1524)
				(type default)
			)
			(layer "F.SilkS")
		)
		(fp_line
			(start -0.67945 -0.305054)
			(end -0.12065 -0.305054)
			(stroke
				(width 0.1)
				(type default)
			)
			(layer "F.Fab")
		)
		(fp_line
			(start -0.67945 0.3048)
			(end -0.67945 -0.305054)
			(stroke
				(width 0.1)
				(type default)
			)
			(layer "F.Fab")
		)
		(fp_line
			(start -0.12065 -0.305054)
			(end -0.12065 -0.2794)
			(stroke
				(width 0.1)
				(type default)
			)
			(layer "F.Fab")
		)
		(fp_line
			(start -0.12065 -0.2794)
			(end 0.12065 -0.2794)
			(stroke
				(width 0.1)
				(type default)
			)
			(layer "F.Fab")
		)
		(fp_line
			(start -0.12065 0.2794)
			(end -0.12065 0.3048)
			(stroke
				(width 0.1)
				(type default)
			)
			(layer "F.Fab")
		)
		(fp_line
			(start -0.12065 0.3048)
			(end -0.67945 0.3048)
			(stroke
				(width 0.1)
				(type default)
			)
			(layer "F.Fab")
		)
		(fp_line
			(start 0.120396 0.2794)
			(end -0.12065 0.2794)
			(stroke
				(width 0.1)
				(type default)
			)
			(layer "F.Fab")
		)
		(fp_line
			(start 0.120396 0.3048)
			(end 0.120396 0.2794)
			(stroke
				(width 0.1)
				(type default)
			)
			(layer "F.Fab")
		)
		(fp_line
			(start 0.12065 -0.3048)
			(end 0.67945 -0.3048)
			(stroke
				(width 0.1)
				(type default)
			)
			(layer "F.Fab")
		)
		(fp_line
			(start 0.12065 -0.2794)
			(end 0.12065 -0.3048)
			(stroke
				(width 0.1)
				(type default)
			)
			(layer "F.Fab")
		)
		(fp_line
			(start 0.67945 -0.3048)
			(end 0.67945 0.3048)
			(stroke
				(width 0.1)
				(type default)
			)
			(layer "F.Fab")
		)
		(fp_line
			(start 0.67945 0.3048)
			(end 0.120396 0.3048)
			(stroke
				(width 0.1)
				(type default)
			)
			(layer "F.Fab")
		)
		(pad "1" smd circle
			(at -0.40005 0)
			(size 0 0)
			(layers "F.Cu" "F.Mask" "F.Paste")
			(net "JTAG_CPU0_BYPASS")
		)
		(pad "2" smd circle
			(at 0.40005 0)
			(size 0 0)
			(layers "F.Cu" "F.Mask" "F.Paste")
			(net "JTAG_CPU0_BYPASS_R1")
		)
	)
)
